(kicad_pcb
	(version 20260206)
	(generator "pcbnew")
	(generator_version "10.0")
	(general
		(thickness 1.6)
		(legacy_teardrops no)
	)
	(paper "A4")
	(title_block
		(title "04192023_DAF0TMB3IC0_F0TG_MB_C_brd_V02_OCP.brd")
		(comment 1 "Grand Teton / footprints 7025-7031 of 8354")
	)
	(layers
		(0 "F.Cu" signal "TOP")
		(4 "In1.Cu" signal "GND")
		(6 "In2.Cu" signal "IN1")
		(8 "In3.Cu" signal "GND1")
		(10 "In4.Cu" signal "IN2")
		(12 "In5.Cu" signal "GND2")
		(14 "In6.Cu" signal "IN3")
		(16 "In7.Cu" signal "GND3")
		(18 "In8.Cu" signal "VCC")
		(20 "In9.Cu" signal "VCC1")
		(22 "In10.Cu" signal "GND4")
		(24 "In11.Cu" signal "IN4")
		(26 "In12.Cu" signal "GND5")
		(28 "In13.Cu" signal "IN5")
		(30 "In14.Cu" signal "GND6")
		(32 "In15.Cu" signal "IN6")
		(34 "In16.Cu" signal "GND7")
		(2 "B.Cu" signal "BOTTOM")
		(9 "F.Adhes" user "F.Adhesive")
		(11 "B.Adhes" user "B.Adhesive")
		(13 "F.Paste" user "Package Geometry/Pastemask Top")
		(15 "B.Paste" user "Package Geometry/Pastemask Bottom")
		(5 "F.SilkS" user "Ref Des/Silkscreen Top")
		(7 "B.SilkS" user "Ref Des/Silkscreen Bottom")
		(1 "F.Mask" user "Board Geometry/Soldermask Top")
		(3 "B.Mask" user "Board Geometry/Soldermask Bottom")
		(17 "Dwgs.User" user "User.Drawings")
		(19 "Cmts.User" user "User.Comments")
		(21 "Eco1.User" user "User.Eco1")
		(23 "Eco2.User" user "User.Eco2")
		(25 "Edge.Cuts" user "Board Geometry/Outline")
		(27 "Margin" user)
		(31 "F.CrtYd" user "Package Geometry/Place Bound Top")
		(29 "B.CrtYd" user "Package Geometry/Place Bound Bottom")
		(35 "F.Fab" user "Ref Des/Assembly Top")
		(33 "B.Fab" user "Ref Des/Assembly Bottom")
	)
	(footprint ""
		(layer "B.Cu")
		(at 404.574502 -152.29078 -90)
		(property "Reference" "R4639"
			(at 0 0 90)
			(layer "B.SilkS")
			(hide yes)
			(effects
				(font
					(size 1.27 1.27)
				)
				(justify mirror)
			)
		)
		(property "Value" ""
			(at 0 0 90)
			(layer "B.Fab")
			(effects
				(font
					(size 1.27 1.27)
				)
				(justify mirror)
			)
		)
		(duplicate_pad_numbers_are_jumpers no)
		(fp_line
			(start -2.234946 0.9271)
			(end 2.234946 0.9271)
			(stroke
				(width 0.1524)
				(type default)
			)
			(layer "B.SilkS")
		)
		(fp_line
			(start 2.234946 0.9271)
			(end 2.234946 -0.9271)
			(stroke
				(width 0.1524)
				(type default)
			)
			(layer "B.SilkS")
		)
		(fp_line
			(start -2.234946 -0.9271)
			(end -2.234946 0.9271)
			(stroke
				(width 0.1524)
				(type default)
			)
			(layer "B.SilkS")
		)
		(fp_line
			(start 2.234946 -0.9271)
			(end -2.234946 -0.9271)
			(stroke
				(width 0.1524)
				(type default)
			)
			(layer "B.SilkS")
		)
		(fp_line
			(start -1.575054 0.824992)
			(end -1.575054 -0.824992)
			(stroke
				(width 0.1)
				(type default)
			)
			(layer "B.Fab")
		)
		(fp_line
			(start 1.575054 0.824992)
			(end -1.575054 0.824992)
			(stroke
				(width 0.1)
				(type default)
			)
			(layer "B.Fab")
		)
		(fp_line
			(start -1.575054 -0.824992)
			(end 1.575054 -0.824992)
			(stroke
				(width 0.1)
				(type default)
			)
			(layer "B.Fab")
		)
		(fp_line
			(start 1.575054 -0.824992)
			(end 1.575054 0.824992)
			(stroke
				(width 0.1)
				(type default)
			)
			(layer "B.Fab")
		)
		(pad "1" smd rect
			(at 1.599946 0 90)
			(size 1.016 1.6002)
			(layers "B.Cu" "B.Mask" "B.Paste")
			(net "P5V")
		)
		(pad "2" smd rect
			(at -1.599946 0 90)
			(size 1.016 1.6002)
			(layers "B.Cu" "B.Mask" "B.Paste")
			(net "VR_P5V_EN_D")
		)
	)
	(footprint ""
		(layer "B.Cu")
		(at 347.389958 -268.41831 180)
		(property "Reference" "C2217"
			(at 0 0 0)
			(layer "B.SilkS")
			(hide yes)
			(effects
				(font
					(size 1.27 1.27)
				)
				(justify mirror)
			)
		)
		(property "Value" ""
			(at 0 0 0)
			(layer "B.Fab")
			(effects
				(font
					(size 1.27 1.27)
				)
				(justify mirror)
			)
		)
		(duplicate_pad_numbers_are_jumpers no)
		(fp_line
			(start 0.7874 0.4064)
			(end 0.7874 -0.4064)
			(stroke
				(width 0.1524)
				(type default)
			)
			(layer "B.SilkS")
		)
		(fp_line
			(start 0.7874 -0.4064)
			(end -0.7874 -0.4064)
			(stroke
				(width 0.1524)
				(type default)
			)
			(layer "B.SilkS")
		)
		(fp_line
			(start -0.7874 0.4064)
			(end 0.7874 0.4064)
			(stroke
				(width 0.1524)
				(type default)
			)
			(layer "B.SilkS")
		)
		(fp_line
			(start -0.7874 -0.4064)
			(end -0.7874 0.4064)
			(stroke
				(width 0.1524)
				(type default)
			)
			(layer "B.SilkS")
		)
		(fp_line
			(start 0.67945 0.3048)
			(end 0.67945 -0.305054)
			(stroke
				(width 0.1)
				(type default)
			)
			(layer "B.Fab")
		)
		(fp_line
			(start 0.67945 -0.305054)
			(end 0.12065 -0.305054)
			(stroke
				(width 0.1)
				(type default)
			)
			(layer "B.Fab")
		)
		(fp_line
			(start 0.12065 0.3048)
			(end 0.67945 0.3048)
			(stroke
				(width 0.1)
				(type default)
			)
			(layer "B.Fab")
		)
		(fp_line
			(start 0.12065 0.2794)
			(end 0.12065 0.3048)
			(stroke
				(width 0.1)
				(type default)
			)
			(layer "B.Fab")
		)
		(fp_line
			(start 0.12065 -0.2794)
			(end -0.12065 -0.2794)
			(stroke
				(width 0.1)
				(type default)
			)
			(layer "B.Fab")
		)
		(fp_line
			(start 0.12065 -0.305054)
			(end 0.12065 -0.2794)
			(stroke
				(width 0.1)
				(type default)
			)
			(layer "B.Fab")
		)
		(fp_line
			(start -0.120396 0.3048)
			(end -0.120396 0.2794)
			(stroke
				(width 0.1)
				(type default)
			)
			(layer "B.Fab")
		)
		(fp_line
			(start -0.120396 0.2794)
			(end 0.12065 0.2794)
			(stroke
				(width 0.1)
				(type default)
			)
			(layer "B.Fab")
		)
		(fp_line
			(start -0.12065 -0.2794)
			(end -0.12065 -0.3048)
			(stroke
				(width 0.1)
				(type default)
			)
			(layer "B.Fab")
		)
		(fp_line
			(start -0.12065 -0.3048)
			(end -0.67945 -0.3048)
			(stroke
				(width 0.1)
				(type default)
			)
			(layer "B.Fab")
		)
		(fp_line
			(start -0.67945 0.3048)
			(end -0.120396 0.3048)
			(stroke
				(width 0.1)
				(type default)
			)
			(layer "B.Fab")
		)
		(fp_line
			(start -0.67945 -0.3048)
			(end -0.67945 0.3048)
			(stroke
				(width 0.1)
				(type default)
			)
			(layer "B.Fab")
		)
		(pad "1" smd circle
			(at 0.40005 0)
			(size 0 0)
			(layers "B.Cu" "B.Mask" "B.Paste")
			(net "PVDDCR_CPU1_P0")
		)
		(pad "2" smd circle
			(at -0.40005 0)
			(size 0 0)
			(layers "B.Cu" "B.Mask" "B.Paste")
			(net "GND")
		)
	)
	(footprint ""
		(layer "B.Cu")
		(at 117.769386 -266.005564)
		(property "Reference" "C2511"
			(at 0 0 0)
			(layer "B.SilkS")
			(hide yes)
			(effects
				(font
					(size 1.27 1.27)
				)
				(justify mirror)
			)
		)
		(property "Value" ""
			(at 0 0 0)
			(layer "B.Fab")
			(effects
				(font
					(size 1.27 1.27)
				)
				(justify mirror)
			)
		)
		(duplicate_pad_numbers_are_jumpers no)
		(fp_line
			(start -0.7874 -0.4064)
			(end -0.7874 0.4064)
			(stroke
				(width 0.1524)
				(type default)
			)
			(layer "B.SilkS")
		)
		(fp_line
			(start -0.7874 0.4064)
			(end 0.7874 0.4064)
			(stroke
				(width 0.1524)
				(type default)
			)
			(layer "B.SilkS")
		)
		(fp_line
			(start 0.7874 -0.4064)
			(end -0.7874 -0.4064)
			(stroke
				(width 0.1524)
				(type default)
			)
			(layer "B.SilkS")
		)
		(fp_line
			(start 0.7874 0.4064)
			(end 0.7874 -0.4064)
			(stroke
				(width 0.1524)
				(type default)
			)
			(layer "B.SilkS")
		)
		(fp_line
			(start -0.67945 -0.3048)
			(end -0.67945 0.3048)
			(stroke
				(width 0.1)
				(type default)
			)
			(layer "B.Fab")
		)
		(fp_line
			(start -0.67945 0.3048)
			(end -0.120396 0.3048)
			(stroke
				(width 0.1)
				(type default)
			)
			(layer "B.Fab")
		)
		(fp_line
			(start -0.12065 -0.3048)
			(end -0.67945 -0.3048)
			(stroke
				(width 0.1)
				(type default)
			)
			(layer "B.Fab")
		)
		(fp_line
			(start -0.12065 -0.2794)
			(end -0.12065 -0.3048)
			(stroke
				(width 0.1)
				(type default)
			)
			(layer "B.Fab")
		)
		(fp_line
			(start -0.120396 0.2794)
			(end 0.12065 0.2794)
			(stroke
				(width 0.1)
				(type default)
			)
			(layer "B.Fab")
		)
		(fp_line
			(start -0.120396 0.3048)
			(end -0.120396 0.2794)
			(stroke
				(width 0.1)
				(type default)
			)
			(layer "B.Fab")
		)
		(fp_line
			(start 0.12065 -0.305054)
			(end 0.12065 -0.2794)
			(stroke
				(width 0.1)
				(type default)
			)
			(layer "B.Fab")
		)
		(fp_line
			(start 0.12065 -0.2794)
			(end -0.12065 -0.2794)
			(stroke
				(width 0.1)
				(type default)
			)
			(layer "B.Fab")
		)
		(fp_line
			(start 0.12065 0.2794)
			(end 0.12065 0.3048)
			(stroke
				(width 0.1)
				(type default)
			)
			(layer "B.Fab")
		)
		(fp_line
			(start 0.12065 0.3048)
			(end 0.67945 0.3048)
			(stroke
				(width 0.1)
				(type default)
			)
			(layer "B.Fab")
		)
		(fp_line
			(start 0.67945 -0.305054)
			(end 0.12065 -0.305054)
			(stroke
				(width 0.1)
				(type default)
			)
			(layer "B.Fab")
		)
		(fp_line
			(start 0.67945 0.3048)
			(end 0.67945 -0.305054)
			(stroke
				(width 0.1)
				(type default)
			)
			(layer "B.Fab")
		)
		(pad "1" smd circle
			(at 0.40005 0 180)
			(size 0 0)
			(layers "B.Cu" "B.Mask" "B.Paste")
			(net "PVDD11_S3_P1")
		)
		(pad "2" smd circle
			(at -0.40005 0 180)
			(size 0 0)
			(layers "B.Cu" "B.Mask" "B.Paste")
			(net "GND")
		)
	)
	(footprint ""
		(layer "B.Cu")
		(at 381.192278 -137.535158 90)
		(property "Reference" "PC13"
			(at 0 0 90)
			(layer "B.SilkS")
			(hide yes)
			(effects
				(font
					(size 1.27 1.27)
				)
				(justify mirror)
			)
		)
		(property "Value" ""
			(at 0 0 90)
			(layer "B.Fab")
			(effects
				(font
					(size 1.27 1.27)
				)
				(justify mirror)
			)
		)
		(duplicate_pad_numbers_are_jumpers no)
		(fp_line
			(start 0.539242 -0.4064)
			(end -0.7874 -0.4064)
			(stroke
				(width 0.1524)
				(type default)
			)
			(layer "B.SilkS")
		)
		(fp_line
			(start -0.7874 -0.4064)
			(end -0.7874 0.4064)
			(stroke
				(width 0.1524)
				(type default)
			)
			(layer "B.SilkS")
		)
		(fp_line
			(start 0.7874 0.4064)
			(end 0.7874 -0.039878)
			(stroke
				(width 0.1524)
				(type default)
			)
			(layer "B.SilkS")
		)
		(fp_line
			(start -0.7874 0.4064)
			(end 0.7874 0.4064)
			(stroke
				(width 0.1524)
				(type default)
			)
			(layer "B.SilkS")
		)
		(fp_line
			(start 0.67945 -0.305054)
			(end 0.12065 -0.305054)
			(stroke
				(width 0.1)
				(type default)
			)
			(layer "B.Fab")
		)
		(fp_line
			(start 0.12065 -0.305054)
			(end 0.12065 -0.2794)
			(stroke
				(width 0.1)
				(type default)
			)
			(layer "B.Fab")
		)
		(fp_line
			(start -0.12065 -0.3048)
			(end -0.67945 -0.3048)
			(stroke
				(width 0.1)
				(type default)
			)
			(layer "B.Fab")
		)
		(fp_line
			(start -0.67945 -0.3048)
			(end -0.67945 0.3048)
			(stroke
				(width 0.1)
				(type default)
			)
			(layer "B.Fab")
		)
		(fp_line
			(start 0.12065 -0.2794)
			(end -0.12065 -0.2794)
			(stroke
				(width 0.1)
				(type default)
			)
			(layer "B.Fab")
		)
		(fp_line
			(start -0.12065 -0.2794)
			(end -0.12065 -0.3048)
			(stroke
				(width 0.1)
				(type default)
			)
			(layer "B.Fab")
		)
		(fp_line
			(start 0.12065 0.2794)
			(end 0.12065 0.3048)
			(stroke
				(width 0.1)
				(type default)
			)
			(layer "B.Fab")
		)
		(fp_line
			(start -0.120396 0.2794)
			(end 0.12065 0.2794)
			(stroke
				(width 0.1)
				(type default)
			)
			(layer "B.Fab")
		)
		(fp_line
			(start 0.67945 0.3048)
			(end 0.67945 -0.305054)
			(stroke
				(width 0.1)
				(type default)
			)
			(layer "B.Fab")
		)
		(fp_line
			(start 0.12065 0.3048)
			(end 0.67945 0.3048)
			(stroke
				(width 0.1)
				(type default)
			)
			(layer "B.Fab")
		)
		(fp_line
			(start -0.120396 0.3048)
			(end -0.120396 0.2794)
			(stroke
				(width 0.1)
				(type default)
			)
			(layer "B.Fab")
		)
		(fp_line
			(start -0.67945 0.3048)
			(end -0.120396 0.3048)
			(stroke
				(width 0.1)
				(type default)
			)
			(layer "B.Fab")
		)
		(pad "1" smd circle
			(at 0.40005 0 270)
			(size 0 0)
			(layers "B.Cu" "B.Mask" "B.Paste")
			(net "PVDDCR_CPU0_P0_VCCS")
		)
		(pad "2" smd circle
			(at -0.40005 0 270)
			(size 0 0)
			(layers "B.Cu" "B.Mask" "B.Paste")
			(net "GND")
		)
	)
	(footprint ""
		(layer "B.Cu")
		(at 342.059006 -416.899344 90)
		(property "Reference" "C6558"
			(at 0 0 90)
			(layer "B.SilkS")
			(hide yes)
			(effects
				(font
					(size 1.27 1.27)
				)
				(justify mirror)
			)
		)
		(property "Value" ""
			(at 0 0 90)
			(layer "B.Fab")
			(effects
				(font
					(size 1.27 1.27)
				)
				(justify mirror)
			)
		)
		(duplicate_pad_numbers_are_jumpers no)
		(fp_line
			(start 0.299974 -0.150114)
			(end -0.299974 -0.150114)
			(stroke
				(width 0.1)
				(type default)
			)
			(layer "B.Fab")
		)
		(fp_line
			(start -0.299974 -0.150114)
			(end -0.299974 0.150114)
			(stroke
				(width 0.1)
				(type default)
			)
			(layer "B.Fab")
		)
		(fp_line
			(start 0.299974 0.150114)
			(end 0.299974 -0.150114)
			(stroke
				(width 0.1)
				(type default)
			)
			(layer "B.Fab")
		)
		(fp_line
			(start -0.299974 0.150114)
			(end 0.299974 0.150114)
			(stroke
				(width 0.1)
				(type default)
			)
			(layer "B.Fab")
		)
		(pad "1" smd rect
			(at 0.2667 0 270)
			(size 0.3048 0.381)
			(layers "B.Cu" "B.Mask" "B.Paste")
			(net "P5E_CPU0_P1_TX_BUF_C_DN<12>")
		)
		(pad "2" smd rect
			(at -0.2667 0 270)
			(size 0.3048 0.381)
			(layers "B.Cu" "B.Mask" "B.Paste")
			(net "P5E_CPU0_P1_TX_BUF_DN<12>")
		)
	)
	(footprint ""
		(layer "B.Cu")
		(at 171.194984 -106.136186)
		(property "Reference" "R165"
			(at 0 0 0)
			(layer "B.SilkS")
			(hide yes)
			(effects
				(font
					(size 1.27 1.27)
				)
				(justify mirror)
			)
		)
		(property "Value" ""
			(at 0 0 0)
			(layer "B.Fab")
			(effects
				(font
					(size 1.27 1.27)
				)
				(justify mirror)
			)
		)
		(duplicate_pad_numbers_are_jumpers no)
		(fp_line
			(start -0.7874 -0.4064)
			(end -0.7874 0.4064)
			(stroke
				(width 0.1524)
				(type default)
			)
			(layer "B.SilkS")
		)
		(fp_line
			(start -0.7874 0.4064)
			(end 0.7874 0.4064)
			(stroke
				(width 0.1524)
				(type default)
			)
			(layer "B.SilkS")
		)
		(fp_line
			(start 0.7874 -0.4064)
			(end -0.7874 -0.4064)
			(stroke
				(width 0.1524)
				(type default)
			)
			(layer "B.SilkS")
		)
		(fp_line
			(start 0.7874 0.4064)
			(end 0.7874 -0.4064)
			(stroke
				(width 0.1524)
				(type default)
			)
			(layer "B.SilkS")
		)
		(fp_line
			(start -0.67945 -0.3048)
			(end -0.67945 0.3048)
			(stroke
				(width 0.1)
				(type default)
			)
			(layer "B.Fab")
		)
		(fp_line
			(start -0.67945 0.3048)
			(end -0.120396 0.3048)
			(stroke
				(width 0.1)
				(type default)
			)
			(layer "B.Fab")
		)
		(fp_line
			(start -0.12065 -0.3048)
			(end -0.67945 -0.3048)
			(stroke
				(width 0.1)
				(type default)
			)
			(layer "B.Fab")
		)
		(fp_line
			(start -0.12065 -0.2794)
			(end -0.12065 -0.3048)
			(stroke
				(width 0.1)
				(type default)
			)
			(layer "B.Fab")
		)
		(fp_line
			(start -0.120396 0.2794)
			(end 0.12065 0.2794)
			(stroke
				(width 0.1)
				(type default)
			)
			(layer "B.Fab")
		)
		(fp_line
			(start -0.120396 0.3048)
			(end -0.120396 0.2794)
			(stroke
				(width 0.1)
				(type default)
			)
			(layer "B.Fab")
		)
		(fp_line
			(start 0.12065 -0.305054)
			(end 0.12065 -0.2794)
			(stroke
				(width 0.1)
				(type default)
			)
			(layer "B.Fab")
		)
		(fp_line
			(start 0.12065 -0.2794)
			(end -0.12065 -0.2794)
			(stroke
				(width 0.1)
				(type default)
			)
			(layer "B.Fab")
		)
		(fp_line
			(start 0.12065 0.2794)
			(end 0.12065 0.3048)
			(stroke
				(width 0.1)
				(type default)
			)
			(layer "B.Fab")
		)
		(fp_line
			(start 0.12065 0.3048)
			(end 0.67945 0.3048)
			(stroke
				(width 0.1)
				(type default)
			)
			(layer "B.Fab")
		)
		(fp_line
			(start 0.67945 -0.305054)
			(end 0.12065 -0.305054)
			(stroke
				(width 0.1)
				(type default)
			)
			(layer "B.Fab")
		)
		(fp_line
			(start 0.67945 0.3048)
			(end 0.67945 -0.305054)
			(stroke
				(width 0.1)
				(type default)
			)
			(layer "B.Fab")
		)
		(pad "1" smd circle
			(at 0.40005 0 180)
			(size 0 0)
			(layers "B.Cu" "B.Mask" "B.Paste")
			(net "FM_I3C_CPU0_MUX1_OE_R_N")
		)
		(pad "2" smd circle
			(at -0.40005 0 180)
			(size 0 0)
			(layers "B.Cu" "B.Mask" "B.Paste")
			(net "FM_I3C_CPU0_MUX1_OE_N")
		)
	)
	(footprint ""
		(layer "B.Cu")
		(at 111.887 -414.02)
		(property "Reference" "R580"
			(at 0 0 0)
			(layer "B.SilkS")
			(hide yes)
			(effects
				(font
					(size 1.27 1.27)
				)
				(justify mirror)
			)
		)
		(property "Value" ""
			(at 0 0 0)
			(layer "B.Fab")
			(effects
				(font
					(size 1.27 1.27)
				)
				(justify mirror)
			)
		)
		(duplicate_pad_numbers_are_jumpers no)
		(fp_line
			(start -0.7874 -0.4064)
			(end -0.7874 0.4064)
			(stroke
				(width 0.1524)
				(type default)
			)
			(layer "B.SilkS")
		)
		(fp_line
			(start -0.7874 0.4064)
			(end 0.7874 0.4064)
			(stroke
				(width 0.1524)
				(type default)
			)
			(layer "B.SilkS")
		)
		(fp_line
			(start 0.7874 -0.4064)
			(end -0.7874 -0.4064)
			(stroke
				(width 0.1524)
				(type default)
			)
			(layer "B.SilkS")
		)
		(fp_line
			(start 0.7874 0.4064)
			(end 0.7874 -0.4064)
			(stroke
				(width 0.1524)
				(type default)
			)
			(layer "B.SilkS")
		)
		(fp_line
			(start -0.67945 -0.3048)
			(end -0.67945 0.3048)
			(stroke
				(width 0.1)
				(type default)
			)
			(layer "B.Fab")
		)
		(fp_line
			(start -0.67945 0.3048)
			(end -0.120396 0.3048)
			(stroke
				(width 0.1)
				(type default)
			)
			(layer "B.Fab")
		)
		(fp_line
			(start -0.12065 -0.3048)
			(end -0.67945 -0.3048)
			(stroke
				(width 0.1)
				(type default)
			)
			(layer "B.Fab")
		)
		(fp_line
			(start -0.12065 -0.2794)
			(end -0.12065 -0.3048)
			(stroke
				(width 0.1)
				(type default)
			)
			(layer "B.Fab")
		)
		(fp_line
			(start -0.120396 0.2794)
			(end 0.12065 0.2794)
			(stroke
				(width 0.1)
				(type default)
			)
			(layer "B.Fab")
		)
		(fp_line
			(start -0.120396 0.3048)
			(end -0.120396 0.2794)
			(stroke
				(width 0.1)
				(type default)
			)
			(layer "B.Fab")
		)
		(fp_line
			(start 0.12065 -0.305054)
			(end 0.12065 -0.2794)
			(stroke
				(width 0.1)
				(type default)
			)
			(layer "B.Fab")
		)
		(fp_line
			(start 0.12065 -0.2794)
			(end -0.12065 -0.2794)
			(stroke
				(width 0.1)
				(type default)
			)
			(layer "B.Fab")
		)
		(fp_line
			(start 0.12065 0.2794)
			(end 0.12065 0.3048)
			(stroke
				(width 0.1)
				(type default)
			)
			(layer "B.Fab")
		)
		(fp_line
			(start 0.12065 0.3048)
			(end 0.67945 0.3048)
			(stroke
				(width 0.1)
				(type default)
			)
			(layer "B.Fab")
		)
		(fp_line
			(start 0.67945 -0.305054)
			(end 0.12065 -0.305054)
			(stroke
				(width 0.1)
				(type default)
			)
			(layer "B.Fab")
		)
		(fp_line
			(start 0.67945 0.3048)
			(end 0.67945 -0.305054)
			(stroke
				(width 0.1)
				(type default)
			)
			(layer "B.Fab")
		)
		(pad "1" smd circle
			(at 0.40005 0 180)
			(size 0 0)
			(layers "B.Cu" "B.Mask" "B.Paste")
			(net "P3V3_AUX")
		)
		(pad "2" smd circle
			(at -0.40005 0 180)
			(size 0 0)
			(layers "B.Cu" "B.Mask" "B.Paste")
			(net "CLK_9ZXL045_P1_HIBW")
		)
	)
)
